FILE_TYPE = CONNECTIVITY;
{Allegro Design Entry HDL 16.6-p007 (v16-6-112F) 10/10/2012}
"PAGE_NUMBER" = 229;
0"NC";
1"GND\g";
2"GND\g";
3"GND\g";
4"GND\g";
5"GND\g";
6"GND\g";
7"GND\g";
8"GND\g";
9"GND\g";
10"P3V3\g";
11"PVTT_GHJ\g";
12"PVTT_GHJ\g";
13"GND\g";
14"P3V3\g";
15"PVDDQ_GHJ\g";
16"PWRGD_PVTT_CPU1";
17"FM_PVTT_GHJ_EN_R";
18"PWRGD_PVTT_GHJ_CPU1_R";
19"VR_PVTT_GHJ_SNS";
20"VSENSE_PVDDQ_GHJ_VTT";
21"VR_PVTT_GHJ_BIAS";
22"VR_PVTT_GHJ_VREF";
23"PWRGD_PVDDQ_GHJ_R";
%"GND"
"1","(-475,-775)","0","mstr_symbols","I1";
;
HDL_POWER"GND"
BODY_TYPE"PLUMBING"
SIZE"1B"
CDS_LIB"mstr_symbols"
VOLTAGE"0.0V";
"A\NAC"1;
%"GND"
"1","(-75,1950)","0","mstr_symbols","I10";
;
ROOM"VTT_GHJ_PWR_VR"
BODY_TYPE"PLUMBING"
BOM_COST"MEM_VRD_VTT_GHJ"
VOLTAGE"0.0V"
CDS_LIB"mstr_symbols"
HDL_POWER"GND"
SIZE"1B";
"A\NAC"2;
%"CAP"
"1","(-75,2200)","0","mstr_discrete","I11";
;
VALUE"10UF"
MATERIAL"X6S"
VOLTAGE"4V"
TOLERANCE"20%"
LOCATION"C6U13"
PART_NUMBER"E15431-001"
PACK_TYPE"0603LF"
SEC"1"
SEC_TYPE"0603LF"
BOM_COST"MEM_VRD_VTT_GHJ"
ROOM"VTT_GHJ_PWR_VR"
CDS_LOCATION"C6U13"
CDS_LIB"mstr_discrete"
CDS_SEC"1";
"A"
$PN"1"15;
"B"
$PN"2"2;
%"SHUNT"
"1","(4850,-150)","0","mstr_misc","I12";
;
LOCATION"SH8U1"
PART_NUMBER"N_A"
SEC_TYPE"SH0201"
CDS_LIB"mstr_misc"
SEC"1"
PACK_TYPE"SH0201"
PIN_SHORT"A:B"
MATERIAL"EMPTY"
CDS_LOCATION"SH8U1"
CDS_SEC"1";
"A"
$PN"1"19;
"B"
$PN"2"12;
%"GND"
"1","(200,600)","0","mstr_symbols","I13";
;
HDL_POWER"GND"
CDS_LIB"mstr_symbols"
SIZE"1B"
BODY_TYPE"PLUMBING"
VOLTAGE"0.0V";
"A\NAC"3;
%"CAP"
"1","(200,825)","0","mstr_discrete","I14";
;
PACK_TYPE"0603"
PART_NUMBER"E15431-003"
MATERIAL"X6S"
TOLERANCE"10%"
VOLTAGE"6.3V"
VALUE"4.7UF"
LOCATION"C6U11"
ROOM"VTT_GHJ_PWR_VR"
SEC"1"
SEC_TYPE"0603"
CDS_LOCATION"C6U11"
CDS_LIB"mstr_discrete"
CDS_SEC"1";
"A"
$PN"1"20;
"B"
$PN"2"3;
%"GND"
"1","(350,1100)","0","mstr_symbols","I15";
;
HDL_POWER"GND"
CDS_LIB"mstr_symbols"
SIZE"1B"
BODY_TYPE"PLUMBING"
VOLTAGE"0.0V";
"A\NAC"4;
%"CAP"
"1","(350,1325)","0","mstr_discrete","I16";
;
VOLTAGE"16V"
LOCATION"C4G18"
VALUE"1.0UF"
TOLERANCE"10%"
MATERIAL"X6S"
PART_NUMBER"D97712-011"
PACK_TYPE"0402"
SEC_TYPE"0402"
BOM_COST"MEM_VRD_VTT_GHJ"
SEC"1"
ROOM"VTT_GHJ_PWR_VR"
CDS_LOCATION"C4G18"
CDS_LIB"mstr_discrete"
CDS_SEC"1";
"A"
$PN"1"21;
"B"
$PN"2"4;
%"GND"
"1","(1875,425)","0","mstr_symbols","I17";
;
HDL_POWER"GND"
BODY_TYPE"PLUMBING"
CDS_LIB"mstr_symbols"
SIZE"1B"
VOLTAGE"0.0V";
"A\NAC"5;
%"CAP"
"1","(350,2200)","0","mstr_discrete","I18";
;
TOLERANCE"20%"
PACK_TYPE"0603LF"
VALUE"10UF"
LOCATION"C6U14"
VOLTAGE"4V"
MATERIAL"X6S"
PART_NUMBER"E15431-001"
SEC"1"
BOM_COST"MEM_VRD_VTT_GHJ"
SEC_TYPE"0603LF"
ROOM"VTT_GHJ_PWR_VR"
CDS_LOCATION"C6U14"
CDS_LIB"mstr_discrete"
CDS_SEC"1";
"A"
$PN"1"15;
"B"
$PN"2"6;
%"GND"
"1","(350,1950)","0","mstr_symbols","I19";
;
HDL_POWER"GND"
SIZE"1B"
CDS_LIB"mstr_symbols"
VOLTAGE"0.0V"
BODY_TYPE"PLUMBING"
BOM_COST"MEM_VRD_VTT_GHJ"
ROOM"VTT_GHJ_PWR_VR";
"A\NAC"6;
%"CAP"
"1","(-475,-550)","2","mstr_discrete","I2";
;
PART_NUMBER"A36096-046"
PACK_TYPE"0402LF"
TOLERANCE"10%"
VOLTAGE"50V"
VALUE"1000PF"
LOCATION"C4G12"
MATERIAL"EMPTY"
ROOM"VTT_GHJ_PWR_VR"
SEC"1"
BOM_COST"MEM_VRD_VTT_GHJ"
SEC_TYPE"0402LF"
CDS_LOCATION"C4G12"
CDS_LIB"mstr_discrete"
CDS_SEC"1";
"A"
$PN"1"17;
"B"
$PN"2"1;
%"GND"
"1","(2200,425)","0","mstr_symbols","I20";
;
SIZE"1B"
HDL_POWER"GND"
BODY_TYPE"PLUMBING"
VOLTAGE"0.0V"
CDS_LIB"mstr_symbols";
"A\NAC"7;
%"CAP"
"1","(2200,675)","0","mstr_discrete","I21";
;
PART_NUMBER"D97712-011"
PACK_TYPE"0402"
MATERIAL"X6S"
TOLERANCE"10%"
VOLTAGE"16V"
VALUE"1.0UF"
LOCATION"C4G21"
SEC"1"
SEC_TYPE"0402"
BOM_COST"MEM_VRD_VTT_GHJ"
ROOM"VTT_GHJ_PWR_VR"
CDS_LOCATION"C4G21"
CDS_LIB"mstr_discrete"
CDS_SEC"1";
"A"
$PN"1"22;
"B"
$PN"2"7;
%"GND"
"1","(3850,500)","0","mstr_symbols","I22";
;
HDL_POWER"GND"
BODY_TYPE"PLUMBING"
CDS_LIB"mstr_symbols"
SIZE"1B"
VOLTAGE"0.0V";
"A\NAC"8;
%"CAP"
"1","(3850,900)","0","mstr_discrete","I23";
;
LOCATION"C4G20"
VALUE"22UF"
PART_NUMBER"C95333-002"
VOLTAGE"4V"
TOLERANCE"20%"
MATERIAL"X6S"
PACK_TYPE"0805LF"
GROUP"PWR_MLCC_CAP"
SEC_TYPE"0805LF"
SEC"1"
BOM_COST"MEM_VRD_VTT_GHJ"
ROOM"VTT_GHJ_PWR_VR"
CDS_LIB"mstr_discrete"
CDS_LOCATION"C4G20"
CDS_SEC"1";
"A"
$PN"1"12;
"B"
$PN"2"8;
%"RES"
"2","(3325,1850)","0","mstr_discrete","I24";
;
LOCATION"R4G17"
PACK_TYPE"0402"
VALUE"10.0K"
TOLERANCE"1%"
WATTAGE"1/16W"
MATERIAL"CHIP"
PART_NUMBER"G21796-016"
CDS_LOCATION"R4G17"
SEC"1"
SEC_TYPE"0402"
BOM_COST"MEM_VRD_VTT_GHJ"
ROOM"VTT_GHJ_PWR_VR"
CDS_LIB"mstr_discrete"
CDS_SEC"1";
"A"
$PN"1"10;
"B"
$PN"2"18;
%"GND"
"1","(3975,1250)","0","mstr_symbols","I25";
;
HDL_POWER"GND"
SIZE"1B"
BODY_TYPE"PLUMBING"
CDS_LIB"mstr_symbols"
VOLTAGE"0.0V";
"A\NAC"9;
%"CAP"
"1","(3975,1450)","2","mstr_discrete","I26";
;
VALUE"1000PF"
TOLERANCE"10%"
PART_NUMBER"A36096-046"
LOCATION"C4G13"
VOLTAGE"50V"
MATERIAL"X7R"
PACK_TYPE"0402LF"
SEC_TYPE"0402LF"
BOM_COST"MEM_VRD_VTT_GHJ"
SEC"1"
ROOM"VTT_GHJ_PWR_VR"
CDS_LIB"mstr_discrete"
CDS_LOCATION"C4G13"
CDS_SEC"1";
"A"
$PN"1"18;
"B"
$PN"2"9;
%"P3V3"
"1","(3325,2075)","0","mstr_symbols","I27";
;
CDS_LIB"mstr_symbols"
SIZE"1B"
VOLTAGE"3.3V"
BODY_TYPE"PLUMBING"
HDL_POWER"P3V3";
"G\NAC"10;
%"CAP_A"
"1","(3400,3200)","0","dev_discrete","I28";
;
MATERIAL"X5R"
TOLERANCE"20%"
VOLTAGE"4V"
LOCATION"C2F2"
PACK_TYPE"0603V"
PART_NUMBER"602433-106"
GROUP"PWR_MLCC_CAP"
VALUE"47UF"
SEC"1"
SEC_TYPE"0603V"
CDS_SEC"1"
CDS_LOCATION"C2F2"
CDS_LIB"dev_discrete";
"B"
$PN"2"13;
"A"
$PN"1"11;
%"PVTT_GHJ"
"1","(3400,3475)","0","mstr_symbols","I29";
;
ROOM"VTT_GHJ_VR"
HDL_POWER"PVTT_GHJ"
BODY_TYPE"PLUMBING"
CDS_LIB"mstr_symbols"
BOM_COST"MEM_VRD_PVDDQ_GHJ"
VOLTAGE"0.6V";
"G\NAC"11;
%"RES"
"1","(4250,1650)","0","mstr_discrete","I32";
;
TOLERANCE"1%"
LOCATION"R4G15"
MATERIAL"CHIP"
PACK_TYPE"0402"
WATTAGE"1/16W"
VALUE"33.2"
PART_NUMBER"G21796-074"
CDS_LOCATION"R4G15"
CDS_LIB"mstr_discrete"
SEC_TYPE"0402"
SEC"1"
CDS_SEC"1";
"B"
$PN"2"16;
"A"
$PN"1"18;
%"PVTT_GHJ"
"1","(5425,1400)","0","mstr_symbols","I34";
;
CDS_LIB"mstr_symbols"
HDL_POWER"PVTT_GHJ"
VOLTAGE"0.6V"
BODY_TYPE"PLUMBING";
"G\NAC"12;
%"GND"
"1","(3400,2875)","0","mstr_symbols","I35";
;
HDL_POWER"GND"
BODY_TYPE"PLUMBING"
SIZE"1B"
CDS_LIB"mstr_symbols"
VOLTAGE"0.0V"
BOM_COST"MEM_VRD_PVDDQ_GHJ"
ROOM"VTT_GHJ_VR";
"A\NAC"13;
%"MIC5166"
"1","(1425,900)","0","mstr_vreg","I37";
;
LOCATION"EU4G2"
MATERIAL"IC"
PART_NUMBER"H55101-001"
SEC"1"
BOM_COST"MEM_VRD_VTT_GHJ"
SEC_TYPE"DFN"
PACK_TYPE"DFN"
ROOM"VTT_GHJ_PWR_VR"
CDS_LIB"mstr_vreg"
CDS_LMAN_SYM_OUTLINE"-250,350,250,-350"
CDS_LOCATION"EU4G2"
CDS_SEC"1";
"THPAD"
$PN"11"5;
"VTT"
$PN"9"12;
"PGND"
$PN"8"5;
"SNS"
$PN"6"19;
"VDDQ"
$PN"4"20;
"PG"
$PN"5"18;
"AGND"
$PN"3"5;
"BIAS"
$PN"2"21;
"VREF"
$PN"1"22;
"VIN"
$PN"10"15;
"EN"
$PN"7"17;
%"RES"
"1","(-650,-25)","0","mstr_discrete","I4";
;
WATTAGE"1/16W"
VALUE"0.0"
TOLERANCE"5%"
PART_NUMBER"G21497-005"
LOCATION"R4G16"
MATERIAL"CHIP"
PACK_TYPE"0402"
ROOM"VTT_GHJ_PWR_VR"
BOM_COST"MEM_VRD_VTT_GHJ"
SEC_TYPE"0402"
SEC"1"
CDS_LOCATION"R4G16"
CDS_LIB"mstr_discrete"
CDS_SEC"1";
"B"
$PN"2"17;
"A"
$PN"1"23;
%"CAP"
"1","(3800,3200)","0","mstr_discrete","I41";
;
LOCATION"C8T3"
PACK_TYPE"0805"
VALUE"100UF"
VOLTAGE"4V"
TOLERANCE"20%"
NEW_MATERIAL"X6S"
PART_NUMBER"602433-112"
GROUP"PWR_MLCC_CAP"
NEW_PN"078.1071T.M002"
MATERIAL"X5R"
SEC"1"
SEC_TYPE"0805"
ROOM"VDDQ_ABC_PWR_VR"
BOM_COST"MEM_VRD_PVDDQ_CD"
CDS_LIB"mstr_discrete"
CDS_SEC"1"
CDS_LOCATION"C8T3";
"A"
$PN"1"11;
"B"
$PN"2"13;
%"CAP"
"1","(4150,3200)","0","mstr_discrete","I42";
;
VOLTAGE"4V"
PART_NUMBER"602433-112"
PACK_TYPE"0805"
VALUE"100UF"
TOLERANCE"20%"
LOCATION"C8U10"
GROUP"PWR_MLCC_CAP"
NEW_MATERIAL"X6S"
NEW_PN"078.1071T.M002"
CDS_SEC"1"
CDS_LIB"mstr_discrete"
BOM_COST"MEM_VRD_PVDDQ_CD"
ROOM"VDDQ_ABC_PWR_VR"
SEC_TYPE"0805"
SEC"1"
MATERIAL"X5R"
CDS_LOCATION"C8U10";
"A"
$PN"1"11;
"B"
$PN"2"13;
%"CAP"
"1","(4700,900)","0","mstr_discrete","I43";
;
PACK_TYPE"0805"
TOLERANCE"20%"
LOCATION"C6W12"
VOLTAGE"4V"
NEW_MATERIAL"X6S"
PART_NUMBER"602433-112"
VALUE"100UF"
GROUP"PWR_MLCC_CAP"
NEW_PN"078.1071T.M002"
MATERIAL"X5R"
SEC"1"
SEC_TYPE"0805"
ROOM"VDDQ_ABC_PWR_VR"
BOM_COST"MEM_VRD_PVDDQ_CD"
CDS_LIB"mstr_discrete"
CDS_SEC"1"
CDS_LOCATION"C6W12";
"A"
$PN"1"12;
"B"
$PN"2"8;
%"RES"
"2","(-425,500)","2","mstr_discrete","I5";
;
PACK_TYPE"0402"
PART_NUMBER"G21796-021"
MATERIAL"EMPTY"
WATTAGE"1/16W"
TOLERANCE"1%"
VALUE"1.0M"
LOCATION"R6U3"
ROOM"VTT_GHJ_PWR_VR"
CDS_LOCATION"R6U3"
SEC"1"
SEC_TYPE"0402"
BOM_COST"MEM_VRD_VTT_GHJ"
CDS_LIB"mstr_discrete"
CDS_SEC"1";
"A"
$PN"1"14;
"B"
$PN"2"17;
%"RES"
"2","(-850,1400)","1","mstr_discrete","I6";
;
LOCATION"R6U6"
TOLERANCE"5%"
VALUE"0.0"
PACK_TYPE"0402"
MATERIAL"CHIP"
WATTAGE"1/16W"
PART_NUMBER"G21497-005"
ROOM"VTT_GHJ_PWR_VR"
NO_XNET_CONNECTION"1"
CDS_LOCATION"R6U6"
SEC"1"
SEC_TYPE"0402"
BOM_COST"MEM_VRD_VTT_GHJ"
CDS_LIB"mstr_discrete"
CDS_SEC"1";
"A"
$PN"1"15;
"B"
$PN"2"20;
%"P3V3"
"1","(-600,1900)","0","mstr_symbols","I7";
;
CDS_LIB"mstr_symbols"
SIZE"1B"
VOLTAGE"3.3V"
BODY_TYPE"PLUMBING"
HDL_POWER"P3V3";
"G\NAC"14;
%"PVDDQ_GHJ"
"1","(-1550,2625)","0","mstr_symbols","I8";
;
VOLTAGE"1.2V"
CDS_LIB"mstr_symbols"
BODY_TYPE"PLUMBING"
HDL_POWER"PVDDQ_GHJ";
"G\NAC"15;
%"RES"
"1","(25,1600)","0","mstr_discrete","I9";
;
LOCATION"R6U7"
PART_NUMBER"G21497-005"
VALUE"0.0"
TOLERANCE"5%"
MATERIAL"CHIP"
WATTAGE"1/16W"
PACK_TYPE"0402"
ROOM"VTT_GHJ_PWR_VR"
CDS_LOCATION"R6U7"
SEC"1"
SEC_TYPE"0402"
BOM_COST"MEM_VRD_VTT_GHJ"
CDS_LIB"mstr_discrete"
CDS_SEC"1";
"B"
$PN"2"21;
"A"
$PN"1"14;
END.
